# BASEBOARD_FAB2 (Tioga Pass) — schematic netlist excerpt (pin names and nets, part order shuffled) for the footprints in the layout excerpt that follows; sources: Cadence DE-HDL packaged netlist, KiCad conversion of Wiwynn_Tioga_Pass_MB.brd

R4P14  RES  240 1.0% CHIP  pkg 0402  page 90 : A = PVCCIO_CPU0 ; B = PU_CPU0_LEGACY_SKT
R1C4  RES  100.0 1% CHIP  pkg 0402  page 210 : A = VSENSE_PVSA_CPU1_N ; B = GND
C8B16  CAP  47UF 4V 20% X6S  pkg 0805  page 131 : A = P1V05_PCH_STBY ; B = GND

(kicad_pcb
	(version 20260206)
	(generator "pcbnew")
	(generator_version "10.0")
	(general
		(thickness 1.6)
		(legacy_teardrops no)
	)
	(paper "A4")
	(title_block
		(title "Wiwynn_Tioga_Pass_MB.brd")
		(comment 1 "Tioga Pass / footprints 4625-4627 of 4770")
	)
	(layers
		(0 "F.Cu" signal "TOP")
		(4 "In1.Cu" signal "L2GND")
		(6 "In2.Cu" signal "L3")
		(8 "In3.Cu" signal "L4GND")
		(10 "In4.Cu" signal "L5")
		(12 "In5.Cu" signal "L6GND")
		(14 "In6.Cu" signal "L7VCC")
		(16 "In7.Cu" signal "L8VCC")
		(18 "In8.Cu" signal "L9GND")
		(20 "In9.Cu" signal "L10")
		(22 "In10.Cu" signal "L11GND")
		(24 "In11.Cu" signal "L12")
		(26 "In12.Cu" signal "L13GND")
		(2 "B.Cu" signal "BOTTOM")
		(9 "F.Adhes" user "F.Adhesive")
		(11 "B.Adhes" user "B.Adhesive")
		(13 "F.Paste" user "Package Geometry/Pastemask Top")
		(15 "B.Paste" user "Package Geometry/Pastemask Bottom")
		(5 "F.SilkS" user "Ref Des/Silkscreen Top")
		(7 "B.SilkS" user "Ref Des/Silkscreen Bottom")
		(1 "F.Mask" user "Board Geometry/Soldermask Top")
		(3 "B.Mask" user "Board Geometry/Soldermask Bottom")
		(17 "Dwgs.User" user "User.Drawings")
		(19 "Cmts.User" user "User.Comments")
		(21 "Eco1.User" user "User.Eco1")
		(23 "Eco2.User" user "User.Eco2")
		(25 "Edge.Cuts" user "Board Geometry/Outline")
		(27 "Margin" user)
		(31 "F.CrtYd" user "Package Geometry/Place Bound Top")
		(29 "B.CrtYd" user "Package Geometry/Place Bound Bottom")
		(35 "F.Fab" user "Ref Des/Assembly Top")
		(33 "B.Fab" user "Ref Des/Assembly Bottom")
	)
	(footprint ""
		(layer "B.Cu")
		(at 279.896824 -70.673214 90)
		(property "Reference" "R4P14"
			(at 0 0 90)
			(layer "B.SilkS")
			(hide yes)
			(effects
				(font
					(size 1.27 1.27)
				)
				(justify mirror)
			)
		)
		(property "Value" ""
			(at 0 0 90)
			(layer "B.Fab")
			(effects
				(font
					(size 1.27 1.27)
				)
				(justify mirror)
			)
		)
		(duplicate_pad_numbers_are_jumpers no)
		(fp_poly
			(pts
				(xy 0.2794 -0.1016) (xy -0.2794 -0.1016) (xy -0.2794 0.9906) (xy 0.2794 0.9906)
			)
			(stroke
				(width 0)
				(type default)
			)
			(fill no)
			(layer "B.CrtYd")
		)
		(fp_line
			(start 0.2794 -0.1016)
			(end 0.2794 0.9906)
			(stroke
				(width 0.1)
				(type default)
			)
			(layer "B.Fab")
		)
		(fp_line
			(start -0.2794 -0.1016)
			(end 0.2794 -0.1016)
			(stroke
				(width 0.1)
				(type default)
			)
			(layer "B.Fab")
		)
		(fp_line
			(start 0.2794 0.9906)
			(end -0.2794 0.9906)
			(stroke
				(width 0.1)
				(type default)
			)
			(layer "B.Fab")
		)
		(fp_line
			(start -0.2794 0.9906)
			(end -0.2794 -0.1016)
			(stroke
				(width 0.1)
				(type default)
			)
			(layer "B.Fab")
		)
		(pad "1" smd rect
			(at 0 0 270)
			(size 0.508 0.508)
			(layers "B.Cu" "B.Mask" "B.Paste")
			(net "PVCCIO_CPU0")
		)
		(pad "2" smd rect
			(at 0 0.889 270)
			(size 0.508 0.508)
			(layers "B.Cu" "B.Mask" "B.Paste")
			(net "PU_CPU0_LEGACY_SKT")
		)
		(zone
			(layer "B.Cu")
			(hatch none 0.5)
			(connect_pads
				(clearance 0)
			)
			(min_thickness 0.25)
			(keepout
				(tracks allowed)
				(vias not_allowed)
				(pads allowed)
				(copperpour not_allowed)
				(footprints allowed)
			)
			(placement
				(enabled no)
				(sheetname "")
			)
			(fill
				(thermal_gap 0.5)
				(thermal_bridge_width 0.5)
				(island_removal_mode 0)
			)
			(polygon
				(pts
					(xy 280.150824 -70.927214) (xy 280.150824 -70.419214) (xy 280.531824 -70.419214) (xy 280.531824 -70.927214)
				)
			)
		)
		(zone
			(layer "B.Cu")
			(hatch none 0.5)
			(connect_pads
				(clearance 0)
			)
			(min_thickness 0.25)
			(keepout
				(tracks not_allowed)
				(vias allowed)
				(pads allowed)
				(copperpour not_allowed)
				(footprints allowed)
			)
			(placement
				(enabled no)
				(sheetname "")
			)
			(fill
				(thermal_gap 0.5)
				(thermal_bridge_width 0.5)
				(island_removal_mode 0)
			)
			(polygon
				(pts
					(xy 280.531824 -70.927214) (xy 280.531824 -70.419214) (xy 280.150824 -70.419214) (xy 280.150824 -70.927214)
				)
			)
		)
	)
	(footprint ""
		(layer "B.Cu")
		(at 411.9626 -121.9962 180)
		(property "Reference" "C8B16"
			(at 0 0 0)
			(layer "B.SilkS")
			(hide yes)
			(effects
				(font
					(size 1.27 1.27)
				)
				(justify mirror)
			)
		)
		(property "Value" ""
			(at 0 0 0)
			(layer "B.Fab")
			(effects
				(font
					(size 1.27 1.27)
				)
				(justify mirror)
			)
		)
		(duplicate_pad_numbers_are_jumpers no)
		(fp_rect
			(start -0.7239 1.9939)
			(end 0.7239 -0.2159)
			(stroke
				(width 0)
				(type default)
			)
			(fill no)
			(layer "B.CrtYd")
		)
		(fp_line
			(start 0.7239 1.9939)
			(end -0.7239 1.9939)
			(stroke
				(width 0.1)
				(type default)
			)
			(layer "B.Fab")
		)
		(fp_line
			(start 0.7239 -0.2159)
			(end 0.7239 1.9939)
			(stroke
				(width 0.1)
				(type default)
			)
			(layer "B.Fab")
		)
		(fp_line
			(start -0.7239 1.9939)
			(end -0.7239 -0.2159)
			(stroke
				(width 0.1)
				(type default)
			)
			(layer "B.Fab")
		)
		(fp_line
			(start -0.7239 -0.2159)
			(end 0.7239 -0.2159)
			(stroke
				(width 0.1)
				(type default)
			)
			(layer "B.Fab")
		)
		(pad "1" smd rect
			(at 0 0)
			(size 1.27 1.016)
			(layers "B.Cu" "B.Mask" "B.Paste")
			(net "P1V05_PCH_STBY")
		)
		(pad "2" smd rect
			(at 0 1.778)
			(size 1.27 1.016)
			(layers "B.Cu" "B.Mask" "B.Paste")
			(net "GND")
		)
		(zone
			(layer "B.Cu")
			(hatch none 0.5)
			(connect_pads
				(clearance 0)
			)
			(min_thickness 0.25)
			(keepout
				(tracks not_allowed)
				(vias allowed)
				(pads allowed)
				(copperpour not_allowed)
				(footprints allowed)
			)
			(placement
				(enabled no)
				(sheetname "")
			)
			(fill
				(thermal_gap 0.5)
				(thermal_bridge_width 0.5)
				(island_removal_mode 0)
			)
			(polygon
				(pts
					(xy 412.5976 -123.2662) (xy 411.3276 -123.2662) (xy 411.3276 -122.5042) (xy 412.5976 -122.5042)
				)
			)
		)
	)
	(footprint ""
		(layer "B.Cu")
		(at 40.994838 -104.252776 90)
		(property "Reference" "R1C4"
			(at 0 0 90)
			(layer "B.SilkS")
			(hide yes)
			(effects
				(font
					(size 1.27 1.27)
				)
				(justify mirror)
			)
		)
		(property "Value" ""
			(at 0 0 90)
			(layer "B.Fab")
			(effects
				(font
					(size 1.27 1.27)
				)
				(justify mirror)
			)
		)
		(duplicate_pad_numbers_are_jumpers no)
		(fp_poly
			(pts
				(xy 0.2794 -0.1016) (xy -0.2794 -0.1016) (xy -0.2794 0.9906) (xy 0.2794 0.9906)
			)
			(stroke
				(width 0)
				(type default)
			)
			(fill no)
			(layer "B.CrtYd")
		)
		(fp_line
			(start 0.2794 -0.1016)
			(end 0.2794 0.9906)
			(stroke
				(width 0.1)
				(type default)
			)
			(layer "B.Fab")
		)
		(fp_line
			(start -0.2794 -0.1016)
			(end 0.2794 -0.1016)
			(stroke
				(width 0.1)
				(type default)
			)
			(layer "B.Fab")
		)
		(fp_line
			(start 0.2794 0.9906)
			(end -0.2794 0.9906)
			(stroke
				(width 0.1)
				(type default)
			)
			(layer "B.Fab")
		)
		(fp_line
			(start -0.2794 0.9906)
			(end -0.2794 -0.1016)
			(stroke
				(width 0.1)
				(type default)
			)
			(layer "B.Fab")
		)
		(pad "1" smd rect
			(at 0 0 270)
			(size 0.508 0.508)
			(layers "B.Cu" "B.Mask" "B.Paste")
			(net "VSENSE_PVSA_CPU1_N")
		)
		(pad "2" smd rect
			(at 0 0.889 270)
			(size 0.508 0.508)
			(layers "B.Cu" "B.Mask" "B.Paste")
			(net "GND")
		)
		(zone
			(layer "B.Cu")
			(hatch none 0.5)
			(connect_pads
				(clearance 0)
			)
			(min_thickness 0.25)
			(keepout
				(tracks allowed)
				(vias not_allowed)
				(pads allowed)
				(copperpour not_allowed)
				(footprints allowed)
			)
			(placement
				(enabled no)
				(sheetname "")
			)
			(fill
				(thermal_gap 0.5)
				(thermal_bridge_width 0.5)
				(island_removal_mode 0)
			)
			(polygon
				(pts
					(xy 41.248838 -104.506776) (xy 41.248838 -103.998776) (xy 41.629838 -103.998776) (xy 41.629838 -104.506776)
				)
			)
		)
		(zone
			(layer "B.Cu")
			(hatch none 0.5)
			(connect_pads
				(clearance 0)
			)
			(min_thickness 0.25)
			(keepout
				(tracks not_allowed)
				(vias allowed)
				(pads allowed)
				(copperpour not_allowed)
				(footprints allowed)
			)
			(placement
				(enabled no)
				(sheetname "")
			)
			(fill
				(thermal_gap 0.5)
				(thermal_bridge_width 0.5)
				(island_removal_mode 0)
			)
			(polygon
				(pts
					(xy 41.629838 -104.506776) (xy 41.629838 -103.998776) (xy 41.248838 -103.998776) (xy 41.248838 -104.506776)
				)
			)
		)
	)
)
